(kicad_pcb
	(version 20260206)
	(generator "pcbnew")
	(generator_version "10.0")
	(general
		(thickness 1.6)
		(legacy_teardrops no)
	)
	(paper "A4")
	(title_block
		(title "04192023_DAF0TMB3IC0_F0TG_MB_C_brd_V02_OCP.brd")
		(comment 1 "Grand Teton / footprints 3237-3243 of 8354")
	)
	(layers
		(0 "F.Cu" signal "TOP")
		(4 "In1.Cu" signal "GND")
		(6 "In2.Cu" signal "IN1")
		(8 "In3.Cu" signal "GND1")
		(10 "In4.Cu" signal "IN2")
		(12 "In5.Cu" signal "GND2")
		(14 "In6.Cu" signal "IN3")
		(16 "In7.Cu" signal "GND3")
		(18 "In8.Cu" signal "VCC")
		(20 "In9.Cu" signal "VCC1")
		(22 "In10.Cu" signal "GND4")
		(24 "In11.Cu" signal "IN4")
		(26 "In12.Cu" signal "GND5")
		(28 "In13.Cu" signal "IN5")
		(30 "In14.Cu" signal "GND6")
		(32 "In15.Cu" signal "IN6")
		(34 "In16.Cu" signal "GND7")
		(2 "B.Cu" signal "BOTTOM")
		(9 "F.Adhes" user "F.Adhesive")
		(11 "B.Adhes" user "B.Adhesive")
		(13 "F.Paste" user "Package Geometry/Pastemask Top")
		(15 "B.Paste" user "Package Geometry/Pastemask Bottom")
		(5 "F.SilkS" user "Ref Des/Silkscreen Top")
		(7 "B.SilkS" user "Ref Des/Silkscreen Bottom")
		(1 "F.Mask" user "Board Geometry/Soldermask Top")
		(3 "B.Mask" user "Board Geometry/Soldermask Bottom")
		(17 "Dwgs.User" user "User.Drawings")
		(19 "Cmts.User" user "User.Comments")
		(21 "Eco1.User" user "User.Eco1")
		(23 "Eco2.User" user "User.Eco2")
		(25 "Edge.Cuts" user "Board Geometry/Outline")
		(27 "Margin" user)
		(31 "F.CrtYd" user "Package Geometry/Place Bound Top")
		(29 "B.CrtYd" user "Package Geometry/Place Bound Bottom")
		(35 "F.Fab" user "Ref Des/Assembly Top")
		(33 "B.Fab" user "Ref Des/Assembly Bottom")
	)
	(footprint ""
		(layer "F.Cu")
		(at 308.716172 -111.60125)
		(property "Reference" "U1"
			(at -2.1082 -3.165348 0)
			(unlocked yes)
			(layer "F.SilkS")
			(effects
				(font
					(size 0.7874 0.5842)
					(thickness 0.1524)
				)
				(justify left)
			)
		)
		(property "Value" ""
			(at 0 0 0)
			(layer "F.Fab")
			(effects
				(font
					(size 1.27 1.27)
				)
			)
		)
		(duplicate_pad_numbers_are_jumpers no)
		(fp_line
			(start -1.8288 -2.500122)
			(end -1.8288 2.500122)
			(stroke
				(width 0.1524)
				(type default)
			)
			(layer "F.SilkS")
		)
		(fp_line
			(start -1.8288 2.500122)
			(end 1.8288 2.500122)
			(stroke
				(width 0.1524)
				(type default)
			)
			(layer "F.SilkS")
		)
		(fp_line
			(start -1.077722 -2.500122)
			(end -1.8288 -2.500122)
			(stroke
				(width 0.1524)
				(type default)
			)
			(layer "F.SilkS")
		)
		(fp_line
			(start 0 -1.4224)
			(end -1.077722 -2.500122)
			(stroke
				(width 0.1524)
				(type default)
			)
			(layer "F.SilkS")
		)
		(fp_line
			(start 1.077722 -2.500122)
			(end 0 -1.4224)
			(stroke
				(width 0.1524)
				(type default)
			)
			(layer "F.SilkS")
		)
		(fp_line
			(start 1.8288 -2.500122)
			(end 1.077722 -2.500122)
			(stroke
				(width 0.1524)
				(type default)
			)
			(layer "F.SilkS")
		)
		(fp_line
			(start 1.8288 2.500122)
			(end 1.8288 -2.500122)
			(stroke
				(width 0.1524)
				(type default)
			)
			(layer "F.SilkS")
		)
		(fp_poly
			(pts
				(xy -3.59791 -2.765044) (xy -4.675632 -3.1242) (xy -3.95732 -3.842766)
			)
			(stroke
				(width 0)
				(type default)
			)
			(fill yes)
			(layer "F.SilkS")
		)
		(fp_line
			(start -1.999996 -2.500122)
			(end -1.999996 2.500122)
			(stroke
				(width 0.1)
				(type default)
			)
			(layer "F.Fab")
		)
		(fp_line
			(start -1.999996 2.500122)
			(end 1.999996 2.500122)
			(stroke
				(width 0.1)
				(type default)
			)
			(layer "F.Fab")
		)
		(fp_line
			(start 1.999996 -2.500122)
			(end -1.999996 -2.500122)
			(stroke
				(width 0.1)
				(type default)
			)
			(layer "F.Fab")
		)
		(fp_line
			(start 1.999996 2.500122)
			(end 1.999996 -2.500122)
			(stroke
				(width 0.1)
				(type default)
			)
			(layer "F.Fab")
		)
		(fp_poly
			(pts
				(xy -4.5085 -2.413) (xy -4.5085 -1.397) (xy -3.4925 -1.905)
			)
			(stroke
				(width 0)
				(type default)
			)
			(fill yes)
			(layer "F.Fab")
		)
		(pad "1" smd rect
			(at -2.599944 -1.905 270)
			(size 0.889 1.27)
			(layers "F.Cu" "F.Mask" "F.Paste")
			(net "CPU_FRU_ADDR0")
		)
		(pad "2" smd rect
			(at -2.599944 -0.635 270)
			(size 0.889 1.27)
			(layers "F.Cu" "F.Mask" "F.Paste")
			(net "CPU_FRU_ADDR1")
		)
		(pad "3" smd rect
			(at -2.599944 0.635 270)
			(size 0.889 1.27)
			(layers "F.Cu" "F.Mask" "F.Paste")
			(net "CPU_FRU_ADDR2")
		)
		(pad "4" smd rect
			(at -2.599944 1.905 270)
			(size 0.889 1.27)
			(layers "F.Cu" "F.Mask" "F.Paste")
			(net "GND")
		)
		(pad "5" smd rect
			(at 2.599944 1.905 270)
			(size 0.889 1.27)
			(layers "F.Cu" "F.Mask" "F.Paste")
			(net "SMB_CPU_FRU_3V3AUX_SDA")
		)
		(pad "6" smd rect
			(at 2.599944 0.635 270)
			(size 0.889 1.27)
			(layers "F.Cu" "F.Mask" "F.Paste")
			(net "SMB_CPU_FRU_3V3AUX_SCL")
		)
		(pad "7" smd rect
			(at 2.599944 -0.635 270)
			(size 0.889 1.27)
			(layers "F.Cu" "F.Mask" "F.Paste")
			(net "PD_CPU_FRU_WP")
		)
		(pad "8" smd rect
			(at 2.599944 -1.905 270)
			(size 0.889 1.27)
			(layers "F.Cu" "F.Mask" "F.Paste")
			(net "P3V3_AUX")
		)
	)
	(footprint ""
		(layer "F.Cu")
		(at 395.794738 -393.9032 90)
		(property "Reference" "R1099"
			(at 0 0 90)
			(layer "F.SilkS")
			(hide yes)
			(effects
				(font
					(size 1.27 1.27)
				)
			)
		)
		(property "Value" ""
			(at 0 0 90)
			(layer "F.Fab")
			(effects
				(font
					(size 1.27 1.27)
				)
			)
		)
		(duplicate_pad_numbers_are_jumpers no)
		(fp_line
			(start 0.32512 -0.175006)
			(end 0.32512 0.175006)
			(stroke
				(width 0.1)
				(type default)
			)
			(layer "F.Fab")
		)
		(fp_line
			(start -0.32512 -0.175006)
			(end 0.32512 -0.175006)
			(stroke
				(width 0.1)
				(type default)
			)
			(layer "F.Fab")
		)
		(fp_line
			(start 0.32512 0.175006)
			(end -0.32512 0.175006)
			(stroke
				(width 0.1)
				(type default)
			)
			(layer "F.Fab")
		)
		(fp_line
			(start -0.32512 0.175006)
			(end -0.32512 -0.175006)
			(stroke
				(width 0.1)
				(type default)
			)
			(layer "F.Fab")
		)
		(pad "1" smd rect
			(at -0.2667 0 90)
			(size 0.3048 0.381)
			(layers "F.Cu" "F.Mask" "F.Paste")
			(net "P1V8_CPU0_RT_1D")
		)
		(pad "2" smd rect
			(at 0.2667 0 270)
			(size 0.3048 0.381)
			(layers "F.Cu" "F.Mask" "F.Paste")
			(net "RT_CPU0_P3_ADDR2")
		)
	)
	(footprint ""
		(layer "F.Cu")
		(at 211.102956 -30.276292 90)
		(property "Reference" "R3613"
			(at 0 0 90)
			(layer "F.SilkS")
			(hide yes)
			(effects
				(font
					(size 1.27 1.27)
				)
			)
		)
		(property "Value" ""
			(at 0 0 90)
			(layer "F.Fab")
			(effects
				(font
					(size 1.27 1.27)
				)
			)
		)
		(duplicate_pad_numbers_are_jumpers no)
		(fp_line
			(start 0.7874 -0.4064)
			(end 0.7874 0.4064)
			(stroke
				(width 0.1524)
				(type default)
			)
			(layer "F.SilkS")
		)
		(fp_line
			(start -0.7874 -0.4064)
			(end 0.7874 -0.4064)
			(stroke
				(width 0.1524)
				(type default)
			)
			(layer "F.SilkS")
		)
		(fp_line
			(start 0.7874 0.4064)
			(end -0.7874 0.4064)
			(stroke
				(width 0.1524)
				(type default)
			)
			(layer "F.SilkS")
		)
		(fp_line
			(start -0.7874 0.4064)
			(end -0.7874 -0.4064)
			(stroke
				(width 0.1524)
				(type default)
			)
			(layer "F.SilkS")
		)
		(fp_line
			(start -0.12065 -0.305054)
			(end -0.12065 -0.2794)
			(stroke
				(width 0.1)
				(type default)
			)
			(layer "F.Fab")
		)
		(fp_line
			(start -0.67945 -0.305054)
			(end -0.12065 -0.305054)
			(stroke
				(width 0.1)
				(type default)
			)
			(layer "F.Fab")
		)
		(fp_line
			(start 0.67945 -0.3048)
			(end 0.67945 0.3048)
			(stroke
				(width 0.1)
				(type default)
			)
			(layer "F.Fab")
		)
		(fp_line
			(start 0.12065 -0.3048)
			(end 0.67945 -0.3048)
			(stroke
				(width 0.1)
				(type default)
			)
			(layer "F.Fab")
		)
		(fp_line
			(start 0.12065 -0.2794)
			(end 0.12065 -0.3048)
			(stroke
				(width 0.1)
				(type default)
			)
			(layer "F.Fab")
		)
		(fp_line
			(start -0.12065 -0.2794)
			(end 0.12065 -0.2794)
			(stroke
				(width 0.1)
				(type default)
			)
			(layer "F.Fab")
		)
		(fp_line
			(start 0.120396 0.2794)
			(end -0.12065 0.2794)
			(stroke
				(width 0.1)
				(type default)
			)
			(layer "F.Fab")
		)
		(fp_line
			(start -0.12065 0.2794)
			(end -0.12065 0.3048)
			(stroke
				(width 0.1)
				(type default)
			)
			(layer "F.Fab")
		)
		(fp_line
			(start 0.67945 0.3048)
			(end 0.120396 0.3048)
			(stroke
				(width 0.1)
				(type default)
			)
			(layer "F.Fab")
		)
		(fp_line
			(start 0.120396 0.3048)
			(end 0.120396 0.2794)
			(stroke
				(width 0.1)
				(type default)
			)
			(layer "F.Fab")
		)
		(fp_line
			(start -0.12065 0.3048)
			(end -0.67945 0.3048)
			(stroke
				(width 0.1)
				(type default)
			)
			(layer "F.Fab")
		)
		(fp_line
			(start -0.67945 0.3048)
			(end -0.67945 -0.305054)
			(stroke
				(width 0.1)
				(type default)
			)
			(layer "F.Fab")
		)
		(pad "1" smd circle
			(at -0.40005 0 90)
			(size 0 0)
			(layers "F.Cu" "F.Mask" "F.Paste")
			(net "GND")
		)
		(pad "2" smd circle
			(at 0.40005 0 90)
			(size 0 0)
			(layers "F.Cu" "F.Mask" "F.Paste")
			(net "INA230_5_A0")
		)
	)
	(footprint ""
		(layer "F.Cu")
		(at 302.60417 -424.9547)
		(property "Reference" "R4137"
			(at 0 0 0)
			(layer "F.SilkS")
			(hide yes)
			(effects
				(font
					(size 1.27 1.27)
				)
			)
		)
		(property "Value" ""
			(at 0 0 0)
			(layer "F.Fab")
			(effects
				(font
					(size 1.27 1.27)
				)
			)
		)
		(duplicate_pad_numbers_are_jumpers no)
		(fp_line
			(start -0.7874 -0.4064)
			(end 0.7874 -0.4064)
			(stroke
				(width 0.1524)
				(type default)
			)
			(layer "F.SilkS")
		)
		(fp_line
			(start -0.7874 0.4064)
			(end -0.7874 -0.4064)
			(stroke
				(width 0.1524)
				(type default)
			)
			(layer "F.SilkS")
		)
		(fp_line
			(start 0.7874 -0.4064)
			(end 0.7874 0.4064)
			(stroke
				(width 0.1524)
				(type default)
			)
			(layer "F.SilkS")
		)
		(fp_line
			(start 0.7874 0.4064)
			(end -0.7874 0.4064)
			(stroke
				(width 0.1524)
				(type default)
			)
			(layer "F.SilkS")
		)
		(fp_line
			(start -0.67945 -0.305054)
			(end -0.12065 -0.305054)
			(stroke
				(width 0.1)
				(type default)
			)
			(layer "F.Fab")
		)
		(fp_line
			(start -0.67945 0.3048)
			(end -0.67945 -0.305054)
			(stroke
				(width 0.1)
				(type default)
			)
			(layer "F.Fab")
		)
		(fp_line
			(start -0.12065 -0.305054)
			(end -0.12065 -0.2794)
			(stroke
				(width 0.1)
				(type default)
			)
			(layer "F.Fab")
		)
		(fp_line
			(start -0.12065 -0.2794)
			(end 0.12065 -0.2794)
			(stroke
				(width 0.1)
				(type default)
			)
			(layer "F.Fab")
		)
		(fp_line
			(start -0.12065 0.2794)
			(end -0.12065 0.3048)
			(stroke
				(width 0.1)
				(type default)
			)
			(layer "F.Fab")
		)
		(fp_line
			(start -0.12065 0.3048)
			(end -0.67945 0.3048)
			(stroke
				(width 0.1)
				(type default)
			)
			(layer "F.Fab")
		)
		(fp_line
			(start 0.120396 0.2794)
			(end -0.12065 0.2794)
			(stroke
				(width 0.1)
				(type default)
			)
			(layer "F.Fab")
		)
		(fp_line
			(start 0.120396 0.3048)
			(end 0.120396 0.2794)
			(stroke
				(width 0.1)
				(type default)
			)
			(layer "F.Fab")
		)
		(fp_line
			(start 0.12065 -0.3048)
			(end 0.67945 -0.3048)
			(stroke
				(width 0.1)
				(type default)
			)
			(layer "F.Fab")
		)
		(fp_line
			(start 0.12065 -0.2794)
			(end 0.12065 -0.3048)
			(stroke
				(width 0.1)
				(type default)
			)
			(layer "F.Fab")
		)
		(fp_line
			(start 0.67945 -0.3048)
			(end 0.67945 0.3048)
			(stroke
				(width 0.1)
				(type default)
			)
			(layer "F.Fab")
		)
		(fp_line
			(start 0.67945 0.3048)
			(end 0.120396 0.3048)
			(stroke
				(width 0.1)
				(type default)
			)
			(layer "F.Fab")
		)
		(pad "1" smd circle
			(at -0.40005 0)
			(size 0 0)
			(layers "F.Cu" "F.Mask" "F.Paste")
			(net "P3V3_AUX")
		)
		(pad "2" smd circle
			(at 0.40005 0)
			(size 0 0)
			(layers "F.Cu" "F.Mask" "F.Paste")
			(net "GPU_3V3IO_RSVD3_FFU_N")
		)
	)
	(footprint ""
		(layer "F.Cu")
		(at 52.78501 -437.642)
		(property "Reference" "R3469"
			(at 0 0 0)
			(layer "F.SilkS")
			(hide yes)
			(effects
				(font
					(size 1.27 1.27)
				)
			)
		)
		(property "Value" ""
			(at 0 0 0)
			(layer "F.Fab")
			(effects
				(font
					(size 1.27 1.27)
				)
			)
		)
		(duplicate_pad_numbers_are_jumpers no)
		(fp_line
			(start -0.7874 -0.4064)
			(end 0.7874 -0.4064)
			(stroke
				(width 0.1524)
				(type default)
			)
			(layer "F.SilkS")
		)
		(fp_line
			(start -0.7874 0.4064)
			(end -0.7874 -0.4064)
			(stroke
				(width 0.1524)
				(type default)
			)
			(layer "F.SilkS")
		)
		(fp_line
			(start 0.7874 -0.4064)
			(end 0.7874 0.4064)
			(stroke
				(width 0.1524)
				(type default)
			)
			(layer "F.SilkS")
		)
		(fp_line
			(start 0.7874 0.4064)
			(end -0.7874 0.4064)
			(stroke
				(width 0.1524)
				(type default)
			)
			(layer "F.SilkS")
		)
		(fp_line
			(start -0.67945 -0.305054)
			(end -0.12065 -0.305054)
			(stroke
				(width 0.1)
				(type default)
			)
			(layer "F.Fab")
		)
		(fp_line
			(start -0.67945 0.3048)
			(end -0.67945 -0.305054)
			(stroke
				(width 0.1)
				(type default)
			)
			(layer "F.Fab")
		)
		(fp_line
			(start -0.12065 -0.305054)
			(end -0.12065 -0.2794)
			(stroke
				(width 0.1)
				(type default)
			)
			(layer "F.Fab")
		)
		(fp_line
			(start -0.12065 -0.2794)
			(end 0.12065 -0.2794)
			(stroke
				(width 0.1)
				(type default)
			)
			(layer "F.Fab")
		)
		(fp_line
			(start -0.12065 0.2794)
			(end -0.12065 0.3048)
			(stroke
				(width 0.1)
				(type default)
			)
			(layer "F.Fab")
		)
		(fp_line
			(start -0.12065 0.3048)
			(end -0.67945 0.3048)
			(stroke
				(width 0.1)
				(type default)
			)
			(layer "F.Fab")
		)
		(fp_line
			(start 0.120396 0.2794)
			(end -0.12065 0.2794)
			(stroke
				(width 0.1)
				(type default)
			)
			(layer "F.Fab")
		)
		(fp_line
			(start 0.120396 0.3048)
			(end 0.120396 0.2794)
			(stroke
				(width 0.1)
				(type default)
			)
			(layer "F.Fab")
		)
		(fp_line
			(start 0.12065 -0.3048)
			(end 0.67945 -0.3048)
			(stroke
				(width 0.1)
				(type default)
			)
			(layer "F.Fab")
		)
		(fp_line
			(start 0.12065 -0.2794)
			(end 0.12065 -0.3048)
			(stroke
				(width 0.1)
				(type default)
			)
			(layer "F.Fab")
		)
		(fp_line
			(start 0.67945 -0.3048)
			(end 0.67945 0.3048)
			(stroke
				(width 0.1)
				(type default)
			)
			(layer "F.Fab")
		)
		(fp_line
			(start 0.67945 0.3048)
			(end 0.120396 0.3048)
			(stroke
				(width 0.1)
				(type default)
			)
			(layer "F.Fab")
		)
		(pad "1" smd circle
			(at -0.40005 0)
			(size 0 0)
			(layers "F.Cu" "F.Mask" "F.Paste")
			(net "RST_PERST_0_SWB_BUF_R_N")
		)
		(pad "2" smd circle
			(at 0.40005 0)
			(size 0 0)
			(layers "F.Cu" "F.Mask" "F.Paste")
			(net "RST_PERST_0_SWB_BUF_N")
		)
	)
	(footprint ""
		(layer "F.Cu")
		(at 343.590626 -416.899344 -90)
		(property "Reference" "C6528"
			(at 0 0 270)
			(layer "F.SilkS")
			(hide yes)
			(effects
				(font
					(size 1.27 1.27)
				)
			)
		)
		(property "Value" ""
			(at 0 0 270)
			(layer "F.Fab")
			(effects
				(font
					(size 1.27 1.27)
				)
			)
		)
		(duplicate_pad_numbers_are_jumpers no)
		(fp_line
			(start -0.299974 0.150114)
			(end -0.299974 -0.150114)
			(stroke
				(width 0.1)
				(type default)
			)
			(layer "F.Fab")
		)
		(fp_line
			(start 0.299974 0.150114)
			(end -0.299974 0.150114)
			(stroke
				(width 0.1)
				(type default)
			)
			(layer "F.Fab")
		)
		(fp_line
			(start -0.299974 -0.150114)
			(end 0.299974 -0.150114)
			(stroke
				(width 0.1)
				(type default)
			)
			(layer "F.Fab")
		)
		(fp_line
			(start 0.299974 -0.150114)
			(end 0.299974 0.150114)
			(stroke
				(width 0.1)
				(type default)
			)
			(layer "F.Fab")
		)
		(pad "1" smd rect
			(at -0.2667 0 270)
			(size 0.3048 0.381)
			(layers "F.Cu" "F.Mask" "F.Paste")
			(net "P5E_CPU0_P0_TX_BUF_C_DN<13>")
		)
		(pad "2" smd rect
			(at 0.2667 0 270)
			(size 0.3048 0.381)
			(layers "F.Cu" "F.Mask" "F.Paste")
			(net "P5E_CPU0_P0_TX_BUF_DN<13>")
		)
	)
	(footprint ""
		(layer "F.Cu")
		(at 117.913912 -17.784064)
		(property "Reference" "C31"
			(at 0 0 0)
			(layer "F.SilkS")
			(hide yes)
			(effects
				(font
					(size 1.27 1.27)
				)
			)
		)
		(property "Value" ""
			(at 0 0 0)
			(layer "F.Fab")
			(effects
				(font
					(size 1.27 1.27)
				)
			)
		)
		(duplicate_pad_numbers_are_jumpers no)
		(fp_line
			(start -0.7874 -0.4064)
			(end 0.7874 -0.4064)
			(stroke
				(width 0.1524)
				(type default)
			)
			(layer "F.SilkS")
		)
		(fp_line
			(start -0.7874 0.4064)
			(end -0.7874 -0.4064)
			(stroke
				(width 0.1524)
				(type default)
			)
			(layer "F.SilkS")
		)
		(fp_line
			(start 0.7874 -0.4064)
			(end 0.7874 0.4064)
			(stroke
				(width 0.1524)
				(type default)
			)
			(layer "F.SilkS")
		)
		(fp_line
			(start 0.7874 0.4064)
			(end -0.7874 0.4064)
			(stroke
				(width 0.1524)
				(type default)
			)
			(layer "F.SilkS")
		)
		(fp_line
			(start -0.67945 -0.305054)
			(end -0.12065 -0.305054)
			(stroke
				(width 0.1)
				(type default)
			)
			(layer "F.Fab")
		)
		(fp_line
			(start -0.67945 0.3048)
			(end -0.67945 -0.305054)
			(stroke
				(width 0.1)
				(type default)
			)
			(layer "F.Fab")
		)
		(fp_line
			(start -0.12065 -0.305054)
			(end -0.12065 -0.2794)
			(stroke
				(width 0.1)
				(type default)
			)
			(layer "F.Fab")
		)
		(fp_line
			(start -0.12065 -0.2794)
			(end 0.12065 -0.2794)
			(stroke
				(width 0.1)
				(type default)
			)
			(layer "F.Fab")
		)
		(fp_line
			(start -0.12065 0.2794)
			(end -0.12065 0.3048)
			(stroke
				(width 0.1)
				(type default)
			)
			(layer "F.Fab")
		)
		(fp_line
			(start -0.12065 0.3048)
			(end -0.67945 0.3048)
			(stroke
				(width 0.1)
				(type default)
			)
			(layer "F.Fab")
		)
		(fp_line
			(start 0.120396 0.2794)
			(end -0.12065 0.2794)
			(stroke
				(width 0.1)
				(type default)
			)
			(layer "F.Fab")
		)
		(fp_line
			(start 0.120396 0.3048)
			(end 0.120396 0.2794)
			(stroke
				(width 0.1)
				(type default)
			)
			(layer "F.Fab")
		)
		(fp_line
			(start 0.12065 -0.3048)
			(end 0.67945 -0.3048)
			(stroke
				(width 0.1)
				(type default)
			)
			(layer "F.Fab")
		)
		(fp_line
			(start 0.12065 -0.2794)
			(end 0.12065 -0.3048)
			(stroke
				(width 0.1)
				(type default)
			)
			(layer "F.Fab")
		)
		(fp_line
			(start 0.67945 -0.3048)
			(end 0.67945 0.3048)
			(stroke
				(width 0.1)
				(type default)
			)
			(layer "F.Fab")
		)
		(fp_line
			(start 0.67945 0.3048)
			(end 0.120396 0.3048)
			(stroke
				(width 0.1)
				(type default)
			)
			(layer "F.Fab")
		)
		(pad "1" smd circle
			(at -0.40005 0)
			(size 0 0)
			(layers "F.Cu" "F.Mask" "F.Paste")
			(net "P3V3_AUX")
		)
		(pad "2" smd circle
			(at 0.40005 0)
			(size 0 0)
			(layers "F.Cu" "F.Mask" "F.Paste")
			(net "GND")
		)
	)
)
